FILE_TYPE = MACRO_DRAWING;
SET COLOR_WIRE YELLOW;
SET COLOR_PROP MONO;
SET COLOR_DOT WHITE;
SET COLOR_ARC YELLOW;
SET COLOR_BODY GREEN;
SET COLOR_NOTE MONO;
SET PROP_DISPLAY VALUE;
SET PAGE_NUMBER P19;
FORCEADD INTEL_CORP_BPAGE..1
(0 0);
FORCEPROP 1 LAST CUSTOM_TXT_CDS <CURRENT_DESIGN_SHEET> OF <TOTAL_DESIGN_SHEETS>
J 0
(-500 25);
PAINT GREEN (-500 25);
FORCEPROP 1 LAST CUSTOM_TXT_CDS <CON_LAST_MODIFIED>
J 0
(-1925 350);
PAINT GREEN (-1925 350);
FORCEPROP 2 LAST CUSTOM_TXT_CDS <XR_PAGE_TITLE>
J 0
(-7890 5250);
DISPLAY 0.638298 (-7890 5250);
PAINT PINK (-7890 5250);
DISPLAY INVISIBLE (-7890 5250);
FORCEPROP 1 LAST SCH_ADDRESS3 Santa Clara, CA 95052-8119
J 0
(-3975 25);
DISPLAY 0.617021 (-3975 25);
PAINT GREEN (-3975 25);
FORCEPROP 1 LAST SCH_ADDRESS1 2200 Mission College Blvd.
J 0
(-3975 125);
DISPLAY 0.617021 (-3975 125);
PAINT GREEN (-3975 125);
FORCEPROP 1 LAST SCH_TITLE PCIE-LANE REVERSAL & POLARITY INV
J 0
(-7950 50);
DISPLAY 1.212766 (-7950 50);
PAINT ORANGE (-7950 50);
FORCEPROP 1 LAST SCH_NUMBER H4694802
J 0
(-1300 150);
DISPLAY 1.212766 (-1300 150);
PAINT YELLOW (-1300 150);
FORCEPROP 1 LAST SCH_REV 2.420
J 0
(-250 150);
DISPLAY 0.978723 (-250 150);
PAINT YELLOW (-250 150);
FORCEPROP 1 LAST SCH_ADDRESS2 P.O. BOX 58119
J 0
(-3975 75);
DISPLAY 0.617021 (-3975 75);
PAINT GREEN (-3975 75);
FORCEPROP 1 LAST SCH_DEPT BESD
J 1
(-4450 100);
DISPLAY 1.212766 (-4450 100);
PAINT YELLOW (-4450 100);
FORCEPROP 2 LAST PAGE_BORDER TRUE
J 0
(-7890 5250);
DISPLAY 0.638298 (-7890 5250);
PAINT PINK (-7890 5250);
DISPLAY INVISIBLE (-7890 5250);
FORCEPROP 2 LAST CDS_LIB mstr_symbols
J 0
(0 0);
PAINT MONO (0 0);
DISPLAY INVISIBLE (0 0);
FORCEPROP 1 LAST COMMENT_BODY TRUE
J 0
(12 12);
DISPLAY 0.468085 (12 12);
PAINT GREEN (12 12);
DISPLAY INVISIBLE (12 12);
FORCEPROP 1 LAST CDS_CON_LAST_MODIFIED Tue Dec 01 11:47:59 2015
J 0
(-1425 325);
PAINT ORANGE (-1425 325);
DISPLAY INVISIBLE (-1425 325);
FORCEPROP 2 LAST CDS_XR_PAGE_TITLE CR-19 : @BASEBOARD_FAB2_LIB.BASEBOARD_FAB2(SCH_1):PAGE19
J 0
(-7890 5250);
DISPLAY 0.638298 (-7890 5250);
PAINT PINK (-7890 5250);
DISPLAY INVISIBLE (-7890 5250);
FORCENOTE
$CDS_IMAGE|clipboard_0.jpg|3625|1125
(-1967 1006) 0;
DISPLAY CENTER (-1967 1006);
PAINT MONO (-1967 1006);
FORCENOTE
$CDS_IMAGE|019_PCIe.jpg|3250|3263
(-1975 3300) 0;
DISPLAY CENTER (-1975 3300);
PAINT MONO (-1975 3300);
FORCENOTE
$CDS_IMAGE|019_PCIe1.jpg|4019|4131
(-5900 2775) 0;
DISPLAY CENTER (-5900 2775);
PAINT MONO (-5900 2775);
QUIT
